G04 ================== begin FILE IDENTIFICATION RECORD ==================*
G04 Layout Name:  15968-1a.brd*
G04 Film Name:    BSILK*
G04 File Format:  Gerber RS274X*
G04 File Origin:  Cadence Allegro 16.5-S058*
G04 Origin Date:  Fri Oct 14 10:23:23 2016*
G04 *
G04 Layer:  VIA CLASS/FILMMASKBOTTOM*
G04 Layer:  REF DES/ASSEMBLY_BOTTOM*
G04 Layer:  PACKAGE GEOMETRY/SILKSCREEN_BOTTOM*
G04 Layer:  DRAWING FORMAT/LAYER_PCB_STORY*
G04 Layer:  DRAWING FORMAT/LAYER_SILK_B*
G04 Layer:  BOARD GEOMETRY/SILKSCREEN_BOTTOM*
G04 *
G04 Offset:    (0.00 0.00)*
G04 Mirror:    No*
G04 Mode:      Positive*
G04 Rotation:  0*
G04 FullContactRelief:  No*
G04 UndefLineWidth:     6.00*
G04 ================== end FILE IDENTIFICATION RECORD ====================*
%FSLAX35Y35*MOIN*%
%IR0*IPPOS*OFA0.00000B0.00000*MIA0B0*SFA1.00000B1.00000*%
%ADD10C,.024*%
%ADD11C,.02*%
%ADD12C,.015*%
%ADD13C,.006*%
%ADD14C,.008*%
G75*
%LPD*%
G75*
G36*
G01X47100Y62900D02*
Y57900D01*
X52100D01*
X47100Y62900D01*
G37*
G54D10*
X104600Y95000D03*
X102400Y92600D03*
X106800Y92700D03*
X104600Y90500D03*
X79000Y142500D03*
X77000Y140300D03*
X81300Y140400D03*
X79200Y138100D03*
X420322Y56072D03*
X423202Y56119D03*
X426128Y50188D03*
Y53348D03*
X426065Y56213D03*
X426113Y59046D03*
X425971Y62050D03*
X432091Y56151D03*
X429056Y56135D03*
X521900Y179500D03*
X524200Y181600D03*
X519700Y181900D03*
X521900Y184000D03*
G54D11*
G01X-84798Y-164972D02*
Y-244972D01*
G01D02*
X1172402D01*
G01X-88798Y-148972D02*
G02I-12000J0D01*
G01X-93948D02*
G02I-6850J0D01*
G01X-100798Y-164972D02*
Y-132972D01*
G01X-84798Y-148972D02*
X-116798D01*
G01X-84798Y-164972D02*
X1172402D01*
G01X-84798Y-200472D02*
X1172402D01*
G01X66500Y83100D02*
Y88100D01*
G01X82600Y26900D02*
X87600D01*
G01Y45700D02*
X82600D01*
G01X79900D02*
X74900D01*
G01Y26900D02*
X79900D01*
G01X384902Y-164972D02*
Y-244972D01*
G01X522402Y-164972D02*
Y-244972D01*
G01X637402Y-164972D02*
Y-244972D01*
G01X804902Y-164972D02*
Y-244972D01*
G01X974902Y-164972D02*
Y-244972D01*
G01X1172402Y-164972D02*
Y-244972D01*
G01X1200402Y-148972D02*
G02I-12000J0D01*
G01X1195252D02*
G02I-6850J0D01*
G01X1188402Y-164972D02*
Y-132972D01*
G01X1204402Y-148972D02*
X1172402D01*
G54D12*
G01X14916Y0D02*
X45625D01*
G01X0Y81561D02*
Y50852D01*
G01Y186482D02*
Y217191D01*
G01X10964Y332539D02*
X41673D01*
G01X51397Y249862D02*
X93906D01*
G01X51397Y241988D02*
X93906D01*
G01X57087Y442487D02*
Y473195D01*
G01X558661Y49363D02*
Y18655D01*
G01X604784Y159311D02*
X574075D01*
G01X564353Y249862D02*
X521844D01*
G01X564353Y241988D02*
X521844D01*
G01X600832Y491850D02*
X570123D01*
G01X615748Y305368D02*
Y274659D01*
G01Y440998D02*
Y410289D01*
G54D13*
G01X-65001Y-234972D02*
Y-217472D01*
X-60635D01*
X-58888Y-218347D01*
X-57578Y-219514D01*
X-56486Y-221263D01*
X-55613Y-223306D01*
X-55395Y-226222D01*
X-55613Y-229139D01*
X-56486Y-231181D01*
X-57578Y-232931D01*
X-58888Y-234097D01*
X-60635Y-234972D01*
X-65001D01*
G01X-48157Y-217472D02*
X-42698Y-234972D01*
X-37239Y-217472D01*
G01X-25198D02*
Y-234972D01*
G01X-30220Y-217472D02*
X-20176D01*
G01X5435Y-234972D02*
Y-217472D01*
X10894D01*
X12640Y-218347D01*
X13732Y-219514D01*
X14169Y-221847D01*
X13732Y-224181D01*
X12422Y-225639D01*
X10894Y-226514D01*
X5435D01*
G01X10894D02*
X14169Y-234972D01*
G01X27302Y-223306D02*
Y-234972D01*
G01Y-218639D02*
X26865Y-218347D01*
Y-217764D01*
X27302Y-217472D01*
X27739Y-217764D01*
Y-218347D01*
X27302Y-218639D01*
G01X41527Y-232931D02*
X42619Y-234097D01*
X44147Y-234972D01*
X45457D01*
X46767Y-234389D01*
X47640Y-233514D01*
X48077Y-232348D01*
X47859Y-230597D01*
X46985Y-229722D01*
X43055Y-227972D01*
X42182Y-225930D01*
X42619Y-224472D01*
X43492Y-223597D01*
X44802Y-223306D01*
X46112Y-223597D01*
X47422Y-224472D01*
G01X59027Y-227097D02*
X66014D01*
X65359Y-225055D01*
X64267Y-223889D01*
X62739Y-223306D01*
X61210Y-223597D01*
X59900Y-224472D01*
X59027Y-226514D01*
X58590Y-228264D01*
Y-230014D01*
X59027Y-231764D01*
X60119Y-233514D01*
X61429Y-234680D01*
X62957Y-234972D01*
X64485Y-234389D01*
X66014Y-232639D01*
G01X76745Y-234972D02*
Y-223306D01*
G01Y-225639D02*
X77837Y-224472D01*
X78929Y-223597D01*
X80457Y-223306D01*
X81548Y-223597D01*
X82859Y-224472D01*
G01X119605Y-218931D02*
X118295Y-218055D01*
X116767Y-217472D01*
X115020D01*
X113055Y-218347D01*
X111527Y-219805D01*
X110435Y-221556D01*
X109562Y-224472D01*
X109343Y-227097D01*
X109780Y-229722D01*
X110435Y-231472D01*
X111745Y-233222D01*
X113274Y-234389D01*
X114802Y-234972D01*
X116330D01*
X117859Y-234389D01*
X119169Y-233514D01*
X120261Y-232348D01*
G01X136232Y-234972D02*
Y-223306D01*
G01Y-225347D02*
X135359Y-224181D01*
X134048Y-223597D01*
X132520Y-223306D01*
X130992Y-223889D01*
X129682Y-225055D01*
X128808Y-226805D01*
X128372Y-229139D01*
X128808Y-231472D01*
X129682Y-233222D01*
X130992Y-234389D01*
X132520Y-234972D01*
X134048Y-234680D01*
X135359Y-233806D01*
X136232Y-232639D01*
G01X146745Y-234972D02*
Y-223306D01*
G01Y-225639D02*
X147837Y-224472D01*
X148929Y-223597D01*
X150457Y-223306D01*
X151548Y-223597D01*
X152859Y-224472D01*
G01X171232Y-217472D02*
Y-234972D01*
G01Y-232348D02*
X170359Y-233806D01*
X169048Y-234680D01*
X167520Y-234972D01*
X165774Y-234389D01*
X164464Y-232931D01*
X163590Y-231181D01*
X163372Y-229139D01*
X163590Y-227097D01*
X164464Y-225347D01*
X165774Y-223889D01*
X167520Y-223306D01*
X169048Y-223597D01*
X170140Y-224181D01*
X171232Y-225347D01*
G01X178252Y-240805D02*
X191352D01*
G01X197717Y-232639D02*
X199464Y-234097D01*
X201429Y-234972D01*
X203175D01*
X204922Y-234097D01*
X206232Y-232639D01*
X206887Y-230597D01*
X206450Y-228556D01*
X205359Y-226805D01*
X203394Y-225639D01*
X200774Y-225055D01*
X199245Y-223889D01*
X198590Y-221847D01*
X199027Y-219805D01*
X200119Y-218347D01*
X201647Y-217472D01*
X203175D01*
X204704Y-218055D01*
X206014Y-219514D01*
G01X215217Y-232639D02*
X216964Y-234097D01*
X218929Y-234972D01*
X220675D01*
X222422Y-234097D01*
X223732Y-232639D01*
X224387Y-230597D01*
X223950Y-228556D01*
X222859Y-226805D01*
X220894Y-225639D01*
X218274Y-225055D01*
X216745Y-223889D01*
X216090Y-221847D01*
X216527Y-219805D01*
X217619Y-218347D01*
X219147Y-217472D01*
X220675D01*
X222204Y-218055D01*
X223514Y-219514D01*
G01X250654Y-220389D02*
X251964Y-218639D01*
X253492Y-217764D01*
X255239Y-217472D01*
X257422Y-218055D01*
X258950Y-219514D01*
X259387Y-221263D01*
X259169Y-223014D01*
X258295Y-224472D01*
X253929Y-227389D01*
X251964Y-229430D01*
X250654Y-232348D01*
X250217Y-234972D01*
X259387D01*
G01X286527Y-232931D02*
X287619Y-234097D01*
X289147Y-234972D01*
X290457D01*
X291767Y-234389D01*
X292640Y-233514D01*
X293077Y-232348D01*
X292859Y-230597D01*
X291985Y-229722D01*
X288055Y-227972D01*
X287182Y-225930D01*
X287619Y-224472D01*
X288492Y-223597D01*
X289802Y-223306D01*
X291112Y-223597D01*
X292422Y-224472D01*
G01X307302Y-234972D02*
Y-217472D01*
G01X324802Y-234972D02*
X323492Y-234680D01*
X322182Y-233514D01*
X321308Y-231472D01*
X320872Y-229139D01*
X321308Y-226805D01*
X322182Y-224764D01*
X323492Y-223597D01*
X324802Y-223306D01*
X326112Y-223597D01*
X327422Y-224764D01*
X328295Y-226805D01*
X328514Y-229139D01*
X328295Y-231472D01*
X327422Y-233514D01*
X326112Y-234680D01*
X324802Y-234972D01*
G01X342302Y-217472D02*
Y-234972D01*
G01X339245Y-223306D02*
X345359D01*
G01X356527Y-232931D02*
X357619Y-234097D01*
X359147Y-234972D01*
X360457D01*
X361767Y-234389D01*
X362640Y-233514D01*
X363077Y-232348D01*
X362859Y-230597D01*
X361985Y-229722D01*
X358055Y-227972D01*
X357182Y-225930D01*
X357619Y-224472D01*
X358492Y-223597D01*
X359802Y-223306D01*
X361112Y-223597D01*
X362422Y-224472D01*
G01X109125Y-189972D02*
Y-172472D01*
X114802Y-187055D01*
X120479Y-172472D01*
Y-189972D01*
G01X132302D02*
X130992Y-189680D01*
X129682Y-188514D01*
X128808Y-186472D01*
X128372Y-184139D01*
X128808Y-181805D01*
X129682Y-179764D01*
X130992Y-178597D01*
X132302Y-178306D01*
X133612Y-178597D01*
X134922Y-179764D01*
X135795Y-181805D01*
X136014Y-184139D01*
X135795Y-186472D01*
X134922Y-188514D01*
X133612Y-189680D01*
X132302Y-189972D01*
G01X153732Y-172472D02*
Y-189972D01*
G01Y-187348D02*
X152859Y-188806D01*
X151548Y-189680D01*
X150020Y-189972D01*
X148274Y-189389D01*
X146964Y-187931D01*
X146090Y-186181D01*
X145872Y-184139D01*
X146090Y-182097D01*
X146964Y-180347D01*
X148274Y-178889D01*
X150020Y-178306D01*
X151548Y-178597D01*
X152640Y-179181D01*
X153732Y-180347D01*
G01X164027Y-182097D02*
X171014D01*
X170359Y-180055D01*
X169267Y-178889D01*
X167739Y-178306D01*
X166210Y-178597D01*
X164900Y-179472D01*
X164027Y-181514D01*
X163590Y-183264D01*
Y-185014D01*
X164027Y-186764D01*
X165119Y-188514D01*
X166429Y-189680D01*
X167957Y-189972D01*
X169485Y-189389D01*
X171014Y-187639D01*
G01X184802Y-189972D02*
Y-172472D01*
G01X418602Y-234972D02*
Y-217472D01*
X415982Y-220972D01*
G01Y-234972D02*
X421222D01*
G01X431299Y-232348D02*
X432608Y-233806D01*
X434137Y-234680D01*
X436102Y-234972D01*
X438067Y-234389D01*
X439595Y-233222D01*
X440687Y-231181D01*
X440905Y-228847D01*
X440469Y-226514D01*
X439377Y-225055D01*
X437848Y-223889D01*
X436320Y-223597D01*
X434792Y-223889D01*
X432827Y-225055D01*
X433482Y-217472D01*
X439377D01*
G01X449890Y-232931D02*
X451419Y-234389D01*
X453165Y-234972D01*
X454912Y-234389D01*
X456440Y-232639D01*
X457532Y-230014D01*
X457969Y-227389D01*
Y-224181D01*
X457532Y-221556D01*
X456440Y-219222D01*
X455130Y-218055D01*
X453602Y-217472D01*
X451855Y-218055D01*
X450545Y-219222D01*
X449672Y-220972D01*
X449235Y-223306D01*
X449672Y-225347D01*
X450764Y-227389D01*
X452074Y-228556D01*
X453602Y-228847D01*
X455348Y-228264D01*
X456659Y-226805D01*
X457969Y-224181D01*
G01X466954Y-227681D02*
X468482Y-225639D01*
X469792Y-224472D01*
X471539Y-223889D01*
X473067Y-224472D01*
X474159Y-225639D01*
X475032Y-227389D01*
X475250Y-229430D01*
X475032Y-231181D01*
X474159Y-232931D01*
X472848Y-234389D01*
X471320Y-234972D01*
X469574Y-234389D01*
X468045Y-232639D01*
X467172Y-230014D01*
X466954Y-227097D01*
X467390Y-223306D01*
X468045Y-221263D01*
X469137Y-219222D01*
X470665Y-217764D01*
X472194Y-217472D01*
X473722Y-218055D01*
X474814Y-219514D01*
G01X488602Y-234972D02*
X490130Y-234680D01*
X491877Y-233806D01*
X492969Y-232348D01*
X493405Y-230305D01*
X492969Y-228264D01*
X491659Y-226514D01*
X489694Y-225639D01*
X487510D01*
X486200Y-225055D01*
X485108Y-223597D01*
X484672Y-221556D01*
X485327Y-219514D01*
X486855Y-218055D01*
X488602Y-217472D01*
X490348Y-218055D01*
X491877Y-219514D01*
X492532Y-221556D01*
X492095Y-223597D01*
X491004Y-225055D01*
X489694Y-225639D01*
X487510D01*
X485545Y-226514D01*
X484235Y-228264D01*
X483799Y-230305D01*
X484235Y-232348D01*
X485327Y-233806D01*
X487074Y-234680D01*
X488602Y-234972D01*
G01X405485Y-189972D02*
Y-172472D01*
X410725D01*
X412472Y-173347D01*
X413782Y-175389D01*
X414219Y-177722D01*
X413782Y-180055D01*
X412690Y-181805D01*
X410725Y-182681D01*
X405485D01*
G01X432155Y-173931D02*
X430845Y-173055D01*
X429317Y-172472D01*
X427570D01*
X425605Y-173347D01*
X424077Y-174805D01*
X422985Y-176556D01*
X422112Y-179472D01*
X421893Y-182097D01*
X422330Y-184722D01*
X422985Y-186472D01*
X424295Y-188222D01*
X425824Y-189389D01*
X427352Y-189972D01*
X428880D01*
X430409Y-189389D01*
X431719Y-188514D01*
X432811Y-187348D01*
G01X446598Y-180639D02*
X447472Y-179764D01*
X448127Y-178306D01*
X448564Y-176263D01*
X448127Y-174514D01*
X447254Y-173347D01*
X445725Y-172472D01*
X439830D01*
Y-189972D01*
X447035D01*
X448564Y-188806D01*
X449437Y-187055D01*
X449874Y-185014D01*
X449437Y-182972D01*
X448127Y-181222D01*
X446598Y-180639D01*
X439830D01*
G01X455802Y-195805D02*
X468902D01*
G01X474830Y-189972D02*
Y-172472D01*
X484874Y-189972D01*
Y-172472D01*
G01X497352Y-189972D02*
X495605Y-189680D01*
X494077Y-188514D01*
X492767Y-186764D01*
X491893Y-184722D01*
X491457Y-182389D01*
Y-180055D01*
X491893Y-177722D01*
X492767Y-175680D01*
X494077Y-173931D01*
X495605Y-172764D01*
X497352Y-172472D01*
X499098Y-172764D01*
X500627Y-173931D01*
X501937Y-175680D01*
X502811Y-177722D01*
X503247Y-180055D01*
Y-182389D01*
X502811Y-184722D01*
X501937Y-186764D01*
X500627Y-188514D01*
X499098Y-189680D01*
X497352Y-189972D01*
G01X571152Y-234972D02*
Y-217472D01*
X568532Y-220972D01*
G01Y-234972D02*
X573772D01*
G01X583193D02*
X588652Y-217472D01*
X594111Y-234972D01*
G01X592145Y-228847D02*
X585158D01*
G01X548193Y-172472D02*
X553652Y-189972D01*
X559111Y-172472D01*
G01X575519Y-189972D02*
X566785D01*
Y-172472D01*
X575519D01*
G01X572025Y-180930D02*
X566785D01*
G01X584285Y-189972D02*
Y-172472D01*
X589744D01*
X591490Y-173347D01*
X592582Y-174514D01*
X593019Y-176847D01*
X592582Y-179181D01*
X591272Y-180639D01*
X589744Y-181514D01*
X584285D01*
G01X589744D02*
X593019Y-189972D01*
G01X606152Y-190555D02*
X605715Y-190264D01*
Y-189680D01*
X606152Y-189389D01*
X606589Y-189680D01*
Y-190264D01*
X606152Y-190555D01*
G01X754356Y-225639D02*
X753482Y-224764D01*
X752827Y-223306D01*
X752390Y-221263D01*
X752827Y-219514D01*
X753700Y-218347D01*
X755229Y-217472D01*
X761124D01*
Y-234972D01*
X753919D01*
X752390Y-233806D01*
X751517Y-232055D01*
X751080Y-230014D01*
X751517Y-227972D01*
X752827Y-226222D01*
X754356Y-225639D01*
X761124D01*
G01X743187Y-232639D02*
X741440Y-234097D01*
X739475Y-234972D01*
X737729D01*
X735982Y-234097D01*
X734672Y-232639D01*
X734017Y-230597D01*
X734454Y-228556D01*
X735545Y-226805D01*
X737510Y-225639D01*
X740130Y-225055D01*
X741659Y-223889D01*
X742314Y-221847D01*
X741877Y-219805D01*
X740785Y-218347D01*
X739257Y-217472D01*
X737729D01*
X736200Y-218055D01*
X734890Y-219514D01*
G01X723722Y-217472D02*
X718482D01*
G01X721102D02*
Y-234972D01*
G01X723722D02*
X718482D01*
G01X707969Y-217472D02*
Y-234972D01*
X699235D01*
G01X690905D02*
Y-217472D01*
G01X682609D02*
X690905Y-228264D01*
G01X681299Y-234972D02*
X687194Y-223306D01*
G01X681735Y-172472D02*
Y-189972D01*
X690469D01*
G01X707532D02*
Y-178306D01*
G01Y-180347D02*
X706659Y-179181D01*
X705348Y-178597D01*
X703820Y-178306D01*
X702292Y-178889D01*
X700982Y-180055D01*
X700108Y-181805D01*
X699672Y-184139D01*
X700108Y-186472D01*
X700982Y-188222D01*
X702292Y-189389D01*
X703820Y-189972D01*
X705348Y-189680D01*
X706659Y-188806D01*
X707532Y-187639D01*
G01X716517Y-195222D02*
X717827Y-195805D01*
X719574Y-195222D01*
X720665Y-194056D01*
X721539Y-192597D01*
X722848Y-187931D01*
X725687Y-178306D01*
G01X718700D02*
X722848Y-187931D01*
G01X735327Y-182097D02*
X742314D01*
X741659Y-180055D01*
X740567Y-178889D01*
X739039Y-178306D01*
X737510Y-178597D01*
X736200Y-179472D01*
X735327Y-181514D01*
X734890Y-183264D01*
Y-185014D01*
X735327Y-186764D01*
X736419Y-188514D01*
X737729Y-189680D01*
X739257Y-189972D01*
X740785Y-189389D01*
X742314Y-187639D01*
G01X753045Y-189972D02*
Y-178306D01*
G01Y-180639D02*
X754137Y-179472D01*
X755229Y-178597D01*
X756757Y-178306D01*
X757848Y-178597D01*
X759159Y-179472D01*
G01X824705Y-218931D02*
X823395Y-218055D01*
X821867Y-217472D01*
X820120D01*
X818155Y-218347D01*
X816627Y-219805D01*
X815535Y-221556D01*
X814662Y-224472D01*
X814443Y-227097D01*
X814880Y-229722D01*
X815535Y-231472D01*
X816845Y-233222D01*
X818374Y-234389D01*
X819902Y-234972D01*
X821430D01*
X822959Y-234389D01*
X824269Y-233514D01*
X825361Y-232348D01*
G01X837402Y-234972D02*
X835655Y-234680D01*
X834127Y-233514D01*
X832817Y-231764D01*
X831943Y-229722D01*
X831507Y-227389D01*
Y-225055D01*
X831943Y-222722D01*
X832817Y-220680D01*
X834127Y-218931D01*
X835655Y-217764D01*
X837402Y-217472D01*
X839148Y-217764D01*
X840677Y-218931D01*
X841987Y-220680D01*
X842861Y-222722D01*
X843297Y-225055D01*
Y-227389D01*
X842861Y-229722D01*
X841987Y-231764D01*
X840677Y-233514D01*
X839148Y-234680D01*
X837402Y-234972D01*
G01X849880D02*
Y-217472D01*
X859924Y-234972D01*
Y-217472D01*
G01X867380Y-234972D02*
Y-217472D01*
X877424Y-234972D01*
Y-217472D01*
G01X887282D02*
X892522D01*
G01X889902D02*
Y-234972D01*
G01X887282D02*
X892522D01*
G01X911769D02*
X903035D01*
Y-217472D01*
X911769D01*
G01X908275Y-225930D02*
X903035D01*
G01X937817Y-234972D02*
X946987Y-217472D01*
G01X937817D02*
X946987Y-234972D01*
G01X955317D02*
Y-217472D01*
G01X964487D02*
Y-234972D01*
G01Y-226222D02*
X955317D01*
G01X823849Y-189972D02*
Y-172472D01*
X828215D01*
X829962Y-173347D01*
X831272Y-174514D01*
X832364Y-176263D01*
X833237Y-178306D01*
X833455Y-181222D01*
X833237Y-184139D01*
X832364Y-186181D01*
X831272Y-187931D01*
X829962Y-189097D01*
X828215Y-189972D01*
X823849D01*
G01X842877Y-182097D02*
X849864D01*
X849209Y-180055D01*
X848117Y-178889D01*
X846589Y-178306D01*
X845060Y-178597D01*
X843750Y-179472D01*
X842877Y-181514D01*
X842440Y-183264D01*
Y-185014D01*
X842877Y-186764D01*
X843969Y-188514D01*
X845279Y-189680D01*
X846807Y-189972D01*
X848335Y-189389D01*
X849864Y-187639D01*
G01X860377Y-187931D02*
X861469Y-189097D01*
X862997Y-189972D01*
X864307D01*
X865617Y-189389D01*
X866490Y-188514D01*
X866927Y-187348D01*
X866709Y-185597D01*
X865835Y-184722D01*
X861905Y-182972D01*
X861032Y-180930D01*
X861469Y-179472D01*
X862342Y-178597D01*
X863652Y-178306D01*
X864962Y-178597D01*
X866272Y-179472D01*
G01X881152Y-178306D02*
Y-189972D01*
G01Y-173639D02*
X880715Y-173347D01*
Y-172764D01*
X881152Y-172472D01*
X881589Y-172764D01*
Y-173347D01*
X881152Y-173639D01*
G01X895595Y-194347D02*
X897124Y-195514D01*
X898870Y-195805D01*
X900398Y-195514D01*
X901709Y-194056D01*
X902582Y-192014D01*
Y-178306D01*
G01Y-180639D02*
X901709Y-179472D01*
X900398Y-178597D01*
X898870Y-178306D01*
X897124Y-178889D01*
X896032Y-180055D01*
X895158Y-182097D01*
X894722Y-184139D01*
X894940Y-185889D01*
X895814Y-187931D01*
X897124Y-189389D01*
X898870Y-189972D01*
X900180Y-189680D01*
X901709Y-188514D01*
X902582Y-187348D01*
G01X912440Y-189972D02*
Y-178306D01*
G01Y-181222D02*
X913314Y-179764D01*
X914624Y-178597D01*
X916370Y-178306D01*
X917898Y-178597D01*
X919209Y-179764D01*
X919864Y-181805D01*
Y-189972D01*
G01X930377Y-182097D02*
X937364D01*
X936709Y-180055D01*
X935617Y-178889D01*
X934089Y-178306D01*
X932560Y-178597D01*
X931250Y-179472D01*
X930377Y-181514D01*
X929940Y-183264D01*
Y-185014D01*
X930377Y-186764D01*
X931469Y-188514D01*
X932779Y-189680D01*
X934307Y-189972D01*
X935835Y-189389D01*
X937364Y-187639D01*
G01X948095Y-189972D02*
Y-178306D01*
G01Y-180639D02*
X949187Y-179472D01*
X950279Y-178597D01*
X951807Y-178306D01*
X952898Y-178597D01*
X954209Y-179472D01*
G01X994852Y-217472D02*
X993105Y-218055D01*
X991795Y-219514D01*
X990922Y-221263D01*
X990267Y-223597D01*
X990049Y-226222D01*
X990267Y-228847D01*
X990922Y-231181D01*
X991795Y-232931D01*
X993105Y-234389D01*
X994852Y-234972D01*
X996598Y-234389D01*
X997909Y-232931D01*
X998782Y-231181D01*
X999437Y-228847D01*
X999655Y-226222D01*
X999437Y-223597D01*
X998782Y-221263D01*
X997909Y-219514D01*
X996598Y-218055D01*
X994852Y-217472D01*
G01X1012352Y-234972D02*
X1013880Y-234680D01*
X1015627Y-233806D01*
X1016719Y-232348D01*
X1017155Y-230305D01*
X1016719Y-228264D01*
X1015409Y-226514D01*
X1013444Y-225639D01*
X1011260D01*
X1009950Y-225055D01*
X1008858Y-223597D01*
X1008422Y-221556D01*
X1009077Y-219514D01*
X1010605Y-218055D01*
X1012352Y-217472D01*
X1014098Y-218055D01*
X1015627Y-219514D01*
X1016282Y-221556D01*
X1015845Y-223597D01*
X1014754Y-225055D01*
X1013444Y-225639D01*
X1011260D01*
X1009295Y-226514D01*
X1007985Y-228264D01*
X1007549Y-230305D01*
X1007985Y-232348D01*
X1009077Y-233806D01*
X1010824Y-234680D01*
X1012352Y-234972D01*
G01X1025922Y-235555D02*
X1033782Y-217472D01*
G01X1043204Y-220389D02*
X1044514Y-218639D01*
X1046042Y-217764D01*
X1047789Y-217472D01*
X1049972Y-218055D01*
X1051500Y-219514D01*
X1051937Y-221263D01*
X1051719Y-223014D01*
X1050845Y-224472D01*
X1046479Y-227389D01*
X1044514Y-229430D01*
X1043204Y-232348D01*
X1042767Y-234972D01*
X1051937D01*
G01X1060049Y-232348D02*
X1061358Y-233806D01*
X1062887Y-234680D01*
X1064852Y-234972D01*
X1066817Y-234389D01*
X1068345Y-233222D01*
X1069437Y-231181D01*
X1069655Y-228847D01*
X1069219Y-226514D01*
X1068127Y-225055D01*
X1066598Y-223889D01*
X1065070Y-223597D01*
X1063542Y-223889D01*
X1061577Y-225055D01*
X1062232Y-217472D01*
X1068127D01*
G01X1078422Y-235555D02*
X1086282Y-217472D01*
G01X1095704Y-220389D02*
X1097014Y-218639D01*
X1098542Y-217764D01*
X1100289Y-217472D01*
X1102472Y-218055D01*
X1104000Y-219514D01*
X1104437Y-221263D01*
X1104219Y-223014D01*
X1103345Y-224472D01*
X1098979Y-227389D01*
X1097014Y-229430D01*
X1095704Y-232348D01*
X1095267Y-234972D01*
X1104437D01*
G01X1117352Y-217472D02*
X1115605Y-218055D01*
X1114295Y-219514D01*
X1113422Y-221263D01*
X1112767Y-223597D01*
X1112549Y-226222D01*
X1112767Y-228847D01*
X1113422Y-231181D01*
X1114295Y-232931D01*
X1115605Y-234389D01*
X1117352Y-234972D01*
X1119098Y-234389D01*
X1120409Y-232931D01*
X1121282Y-231181D01*
X1121937Y-228847D01*
X1122155Y-226222D01*
X1121937Y-223597D01*
X1121282Y-221263D01*
X1120409Y-219514D01*
X1119098Y-218055D01*
X1117352Y-217472D01*
G01X1134852Y-234972D02*
Y-217472D01*
X1132232Y-220972D01*
G01Y-234972D02*
X1137472D01*
G01X1148204Y-227681D02*
X1149732Y-225639D01*
X1151042Y-224472D01*
X1152789Y-223889D01*
X1154317Y-224472D01*
X1155409Y-225639D01*
X1156282Y-227389D01*
X1156500Y-229430D01*
X1156282Y-231181D01*
X1155409Y-232931D01*
X1154098Y-234389D01*
X1152570Y-234972D01*
X1150824Y-234389D01*
X1149295Y-232639D01*
X1148422Y-230014D01*
X1148204Y-227097D01*
X1148640Y-223306D01*
X1149295Y-221263D01*
X1150387Y-219222D01*
X1151915Y-217764D01*
X1153444Y-217472D01*
X1154972Y-218055D01*
X1156064Y-219514D01*
G01X1042549Y-189972D02*
Y-172472D01*
X1046915D01*
X1048662Y-173347D01*
X1049972Y-174514D01*
X1051064Y-176263D01*
X1051937Y-178306D01*
X1052155Y-181222D01*
X1051937Y-184139D01*
X1051064Y-186181D01*
X1049972Y-187931D01*
X1048662Y-189097D01*
X1046915Y-189972D01*
X1042549D01*
G01X1068782D02*
Y-178306D01*
G01Y-180347D02*
X1067909Y-179181D01*
X1066598Y-178597D01*
X1065070Y-178306D01*
X1063542Y-178889D01*
X1062232Y-180055D01*
X1061358Y-181805D01*
X1060922Y-184139D01*
X1061358Y-186472D01*
X1062232Y-188222D01*
X1063542Y-189389D01*
X1065070Y-189972D01*
X1066598Y-189680D01*
X1067909Y-188806D01*
X1068782Y-187639D01*
G01X1082352Y-172472D02*
Y-189972D01*
G01X1079295Y-178306D02*
X1085409D01*
G01X1096577Y-182097D02*
X1103564D01*
X1102909Y-180055D01*
X1101817Y-178889D01*
X1100289Y-178306D01*
X1098760Y-178597D01*
X1097450Y-179472D01*
X1096577Y-181514D01*
X1096140Y-183264D01*
Y-185014D01*
X1096577Y-186764D01*
X1097669Y-188514D01*
X1098979Y-189680D01*
X1100507Y-189972D01*
X1102035Y-189389D01*
X1103564Y-187639D01*
G01X9550Y69267D02*
X12050D01*
Y70267D01*
X11925Y70600D01*
X11633Y70850D01*
X11300Y70933D01*
X10967Y70850D01*
X10717Y70642D01*
X10592Y70267D01*
Y69267D01*
G01X11842Y74117D02*
X11967Y73867D01*
X12050Y73575D01*
Y73242D01*
X11925Y72867D01*
X11717Y72575D01*
X11467Y72367D01*
X11050Y72200D01*
X10675Y72158D01*
X10300Y72242D01*
X10050Y72367D01*
X9800Y72617D01*
X9633Y72908D01*
X9550Y73200D01*
Y73492D01*
X9633Y73783D01*
X9758Y74033D01*
X9925Y74242D01*
G01X9550Y76300D02*
X12050D01*
X11550Y75800D01*
G01X9550D02*
Y76800D01*
G01Y79400D02*
X12050D01*
X11550Y78900D01*
G01X9550D02*
Y79900D01*
G01X18833Y89250D02*
Y91750D01*
X17833D01*
X17500Y91625D01*
X17250Y91333D01*
X17167Y91000D01*
X17250Y90667D01*
X17458Y90417D01*
X17833Y90292D01*
X18833D01*
G01X13983Y91542D02*
X14233Y91667D01*
X14525Y91750D01*
X14858D01*
X15233Y91625D01*
X15525Y91417D01*
X15733Y91167D01*
X15900Y90750D01*
X15942Y90375D01*
X15858Y90000D01*
X15733Y89750D01*
X15483Y89500D01*
X15192Y89333D01*
X14900Y89250D01*
X14608D01*
X14317Y89333D01*
X14067Y89458D01*
X13858Y89625D01*
G01X11800Y89250D02*
Y91750D01*
X12300Y91250D01*
G01Y89250D02*
X11300D01*
G01X8700Y91750D02*
X9033Y91667D01*
X9283Y91458D01*
X9450Y91208D01*
X9575Y90875D01*
X9617Y90500D01*
X9575Y90125D01*
X9450Y89792D01*
X9283Y89542D01*
X9033Y89333D01*
X8700Y89250D01*
X8367Y89333D01*
X8117Y89542D01*
X7950Y89792D01*
X7825Y90125D01*
X7783Y90500D01*
X7825Y90875D01*
X7950Y91208D01*
X8117Y91458D01*
X8367Y91667D01*
X8700Y91750D01*
G01X26901Y52317D02*
Y54817D01*
X25901D01*
X25568Y54692D01*
X25318Y54400D01*
X25235Y54067D01*
X25318Y53734D01*
X25526Y53484D01*
X25901Y53359D01*
X26901D01*
G01X22051Y54609D02*
X22301Y54734D01*
X22593Y54817D01*
X22926D01*
X23301Y54692D01*
X23593Y54484D01*
X23801Y54234D01*
X23968Y53817D01*
X24010Y53442D01*
X23926Y53067D01*
X23801Y52817D01*
X23551Y52567D01*
X23260Y52400D01*
X22968Y52317D01*
X22676D01*
X22385Y52400D01*
X22135Y52525D01*
X21926Y52692D01*
G01X20785Y52817D02*
X20535Y52525D01*
X20201Y52359D01*
X19826Y52317D01*
X19493Y52359D01*
X19160Y52567D01*
X18951Y52817D01*
X18910Y53067D01*
X18993Y53359D01*
X19285Y53567D01*
X19576Y53650D01*
X19951D01*
G01X19576D02*
X19326Y53775D01*
X19118Y53984D01*
X19035Y54234D01*
X19118Y54484D01*
X19326Y54692D01*
X19701Y54817D01*
X20076Y54775D01*
X20451Y54609D01*
G01X13550Y69567D02*
X16050D01*
Y70567D01*
X15925Y70900D01*
X15633Y71150D01*
X15300Y71233D01*
X14967Y71150D01*
X14717Y70942D01*
X14592Y70567D01*
Y69567D01*
G01X15842Y74417D02*
X15967Y74167D01*
X16050Y73875D01*
Y73542D01*
X15925Y73167D01*
X15717Y72875D01*
X15467Y72667D01*
X15050Y72500D01*
X14675Y72458D01*
X14300Y72542D01*
X14050Y72667D01*
X13800Y72917D01*
X13633Y73208D01*
X13550Y73500D01*
Y73792D01*
X13633Y74083D01*
X13758Y74333D01*
X13925Y74542D01*
G01X13550Y76600D02*
X16050D01*
X15550Y76100D01*
G01X13550D02*
Y77100D01*
G01X13925Y78783D02*
X13717Y79033D01*
X13592Y79325D01*
X13550Y79700D01*
X13633Y80075D01*
X13800Y80367D01*
X14092Y80575D01*
X14425Y80617D01*
X14758Y80533D01*
X14967Y80325D01*
X15133Y80033D01*
X15175Y79742D01*
X15133Y79450D01*
X14967Y79075D01*
X16050Y79200D01*
Y80325D01*
G01X14081Y81724D02*
Y84224D01*
X13081D01*
X12748Y84099D01*
X12498Y83807D01*
X12415Y83474D01*
X12498Y83141D01*
X12706Y82891D01*
X13081Y82766D01*
X14081D01*
G01X10981Y81724D02*
Y84224D01*
X9940D01*
X9606Y84099D01*
X9398Y83932D01*
X9315Y83599D01*
X9398Y83266D01*
X9648Y83057D01*
X9940Y82932D01*
X10981D01*
G01X9940D02*
X9315Y81724D01*
G01X6548D02*
Y84224D01*
X8090Y82432D01*
X6006D01*
G01X13924Y53319D02*
X16424D01*
Y54319D01*
X16299Y54652D01*
X16007Y54902D01*
X15674Y54985D01*
X15341Y54902D01*
X15091Y54694D01*
X14966Y54319D01*
Y53319D01*
G01X13924Y56419D02*
X16424D01*
Y57460D01*
X16299Y57794D01*
X16132Y58002D01*
X15799Y58085D01*
X15466Y58002D01*
X15257Y57752D01*
X15132Y57460D01*
Y56419D01*
G01Y57460D02*
X13924Y58085D01*
G01Y60269D02*
X14466Y60352D01*
X14924Y60477D01*
X15341Y60644D01*
X15799Y60852D01*
X16424Y61185D01*
Y59519D01*
G01X15581Y65124D02*
Y67624D01*
X14581D01*
X14248Y67499D01*
X13998Y67207D01*
X13915Y66874D01*
X13998Y66541D01*
X14206Y66291D01*
X14581Y66166D01*
X15581D01*
G01X12481Y65124D02*
Y67624D01*
X11440D01*
X11106Y67499D01*
X10898Y67332D01*
X10815Y66999D01*
X10898Y66666D01*
X11148Y66457D01*
X11440Y66332D01*
X12481D01*
G01X11440D02*
X10815Y65124D01*
G01X9340Y66166D02*
X9048Y66457D01*
X8798Y66624D01*
X8465Y66707D01*
X8173Y66624D01*
X7965Y66457D01*
X7798Y66207D01*
X7756Y65916D01*
X7798Y65666D01*
X7965Y65416D01*
X8215Y65207D01*
X8506Y65124D01*
X8840Y65207D01*
X9131Y65457D01*
X9298Y65832D01*
X9340Y66249D01*
X9256Y66791D01*
X9131Y67082D01*
X8923Y67374D01*
X8631Y67582D01*
X8340Y67624D01*
X8048Y67541D01*
X7840Y67332D01*
G01X20124Y76719D02*
X22624D01*
Y77719D01*
X22499Y78052D01*
X22207Y78302D01*
X21874Y78385D01*
X21541Y78302D01*
X21291Y78094D01*
X21166Y77719D01*
Y76719D01*
G01X20124Y79819D02*
X22624D01*
Y80860D01*
X22499Y81194D01*
X22332Y81402D01*
X21999Y81485D01*
X21666Y81402D01*
X21457Y81152D01*
X21332Y80860D01*
Y79819D01*
G01Y80860D02*
X20124Y81485D01*
G01X20499Y82835D02*
X20291Y83085D01*
X20166Y83377D01*
X20124Y83752D01*
X20207Y84127D01*
X20374Y84419D01*
X20666Y84627D01*
X20999Y84669D01*
X21332Y84585D01*
X21541Y84377D01*
X21707Y84085D01*
X21749Y83794D01*
X21707Y83502D01*
X21541Y83127D01*
X22624Y83252D01*
Y84377D01*
G01X19181Y85524D02*
Y88024D01*
X18181D01*
X17848Y87899D01*
X17598Y87607D01*
X17515Y87274D01*
X17598Y86941D01*
X17806Y86691D01*
X18181Y86566D01*
X19181D01*
G01X16081Y85524D02*
Y88024D01*
X15040D01*
X14706Y87899D01*
X14498Y87732D01*
X14415Y87399D01*
X14498Y87066D01*
X14748Y86857D01*
X15040Y86732D01*
X16081D01*
G01X15040D02*
X14415Y85524D01*
G01X12856Y85816D02*
X12565Y85607D01*
X12231Y85524D01*
X11898Y85607D01*
X11606Y85857D01*
X11398Y86232D01*
X11315Y86607D01*
Y87066D01*
X11398Y87441D01*
X11606Y87774D01*
X11856Y87941D01*
X12148Y88024D01*
X12481Y87941D01*
X12731Y87774D01*
X12898Y87524D01*
X12981Y87191D01*
X12898Y86899D01*
X12690Y86607D01*
X12440Y86441D01*
X12148Y86399D01*
X11815Y86482D01*
X11565Y86691D01*
X11315Y87066D01*
G01X18383Y93200D02*
Y95700D01*
X17383D01*
X17050Y95575D01*
X16800Y95283D01*
X16717Y94950D01*
X16800Y94617D01*
X17008Y94367D01*
X17383Y94242D01*
X18383D01*
G01X13533Y95492D02*
X13783Y95617D01*
X14075Y95700D01*
X14408D01*
X14783Y95575D01*
X15075Y95367D01*
X15283Y95117D01*
X15450Y94700D01*
X15492Y94325D01*
X15408Y93950D01*
X15283Y93700D01*
X15033Y93450D01*
X14742Y93283D01*
X14450Y93200D01*
X14158D01*
X13867Y93283D01*
X13617Y93408D01*
X13408Y93575D01*
G01X11350Y93200D02*
Y95700D01*
X11850Y95200D01*
G01Y93200D02*
X10850D01*
G01X9167Y93700D02*
X8917Y93408D01*
X8583Y93242D01*
X8208Y93200D01*
X7875Y93242D01*
X7542Y93450D01*
X7333Y93700D01*
X7292Y93950D01*
X7375Y94242D01*
X7667Y94450D01*
X7958Y94533D01*
X8333D01*
G01X7958D02*
X7708Y94658D01*
X7500Y94867D01*
X7417Y95117D01*
X7500Y95367D01*
X7708Y95575D01*
X8083Y95700D01*
X8458Y95658D01*
X8833Y95492D01*
G01X4100Y66367D02*
X6600D01*
Y67367D01*
X6475Y67700D01*
X6183Y67950D01*
X5850Y68033D01*
X5517Y67950D01*
X5267Y67742D01*
X5142Y67367D01*
Y66367D01*
G01X4100Y69467D02*
X6600D01*
Y70508D01*
X6475Y70842D01*
X6308Y71050D01*
X5975Y71133D01*
X5642Y71050D01*
X5433Y70800D01*
X5308Y70508D01*
Y69467D01*
G01Y70508D02*
X4100Y71133D01*
G01X6183Y72608D02*
X6433Y72858D01*
X6558Y73150D01*
X6600Y73483D01*
X6517Y73900D01*
X6308Y74192D01*
X6058Y74275D01*
X5808Y74233D01*
X5600Y74067D01*
X5183Y73233D01*
X4892Y72858D01*
X4475Y72608D01*
X4100Y72525D01*
Y74275D01*
G01X14333Y61500D02*
Y64000D01*
X13333D01*
X13000Y63875D01*
X12750Y63583D01*
X12667Y63250D01*
X12750Y62917D01*
X12958Y62667D01*
X13333Y62542D01*
X14333D01*
G01X10150Y62750D02*
X9317D01*
Y62000D01*
X9567Y61750D01*
X9858Y61583D01*
X10275Y61500D01*
X10692Y61583D01*
X10983Y61750D01*
X11233Y62000D01*
X11400Y62292D01*
X11483Y62625D01*
Y62917D01*
X11400Y63167D01*
X11233Y63458D01*
X10983Y63708D01*
X10733Y63875D01*
X10400Y64000D01*
X10108D01*
X9775Y63917D01*
X9525Y63750D01*
G01X7300Y61500D02*
Y64000D01*
X7800Y63500D01*
G01Y61500D02*
X6800D01*
G01X72400Y54100D02*
X44400D01*
Y18300D01*
X72400D01*
Y54100D01*
G01X39000Y38367D02*
X41500D01*
Y39367D01*
X41375Y39700D01*
X41083Y39950D01*
X40750Y40033D01*
X40417Y39950D01*
X40167Y39742D01*
X40042Y39367D01*
Y38367D01*
G01X41292Y43217D02*
X41417Y42967D01*
X41500Y42675D01*
Y42342D01*
X41375Y41967D01*
X41167Y41675D01*
X40917Y41467D01*
X40500Y41300D01*
X40125Y41258D01*
X39750Y41342D01*
X39500Y41467D01*
X39250Y41717D01*
X39083Y42008D01*
X39000Y42300D01*
Y42592D01*
X39083Y42883D01*
X39208Y43133D01*
X39375Y43342D01*
G01X39000Y45900D02*
X41500D01*
X39708Y44358D01*
Y46442D01*
G01X69733Y90900D02*
Y93400D01*
X68733D01*
X68400Y93275D01*
X68150Y92983D01*
X68067Y92650D01*
X68150Y92317D01*
X68358Y92067D01*
X68733Y91942D01*
X69733D01*
G01X64883Y93192D02*
X65133Y93317D01*
X65425Y93400D01*
X65758D01*
X66133Y93275D01*
X66425Y93067D01*
X66633Y92817D01*
X66800Y92400D01*
X66842Y92025D01*
X66758Y91650D01*
X66633Y91400D01*
X66383Y91150D01*
X66092Y90983D01*
X65800Y90900D01*
X65508D01*
X65217Y90983D01*
X64967Y91108D01*
X64758Y91275D01*
G01X62700Y90900D02*
Y93400D01*
X63200Y92900D01*
G01Y90900D02*
X62200D01*
G01X36600Y81000D02*
Y77000D01*
X29200D01*
G01X97881Y61824D02*
Y64324D01*
X96881D01*
X96548Y64199D01*
X96298Y63907D01*
X96215Y63574D01*
X96298Y63241D01*
X96506Y62991D01*
X96881Y62866D01*
X97881D01*
G01X94781Y61824D02*
Y64324D01*
X93740D01*
X93406Y64199D01*
X93198Y64032D01*
X93115Y63699D01*
X93198Y63366D01*
X93448Y63157D01*
X93740Y63032D01*
X94781D01*
G01X93740D02*
X93115Y61824D01*
G01X91765Y62324D02*
X91515Y62032D01*
X91181Y61866D01*
X90806Y61824D01*
X90473Y61866D01*
X90140Y62074D01*
X89931Y62324D01*
X89890Y62574D01*
X89973Y62866D01*
X90265Y63074D01*
X90556Y63157D01*
X90931D01*
G01X90556D02*
X90306Y63282D01*
X90098Y63491D01*
X90015Y63741D01*
X90098Y63991D01*
X90306Y64199D01*
X90681Y64324D01*
X91056Y64282D01*
X91431Y64116D01*
G01X80700Y62000D02*
Y58000D01*
X73300D01*
G01X34800Y65200D02*
X38800D01*
Y57800D01*
G01X38100Y69300D02*
Y65300D01*
X30700D01*
G01X42500Y76200D02*
X46500D01*
Y68800D01*
G01X35724Y91319D02*
X38224D01*
Y92319D01*
X38099Y92652D01*
X37807Y92902D01*
X37474Y92985D01*
X37141Y92902D01*
X36891Y92694D01*
X36766Y92319D01*
Y91319D01*
G01X35724Y94419D02*
X38224D01*
Y95460D01*
X38099Y95794D01*
X37932Y96002D01*
X37599Y96085D01*
X37266Y96002D01*
X37057Y95752D01*
X36932Y95460D01*
Y94419D01*
G01Y95460D02*
X35724Y96085D01*
G01Y98352D02*
X35766Y98644D01*
X35891Y98977D01*
X36099Y99185D01*
X36391Y99269D01*
X36682Y99185D01*
X36932Y98935D01*
X37057Y98560D01*
Y98144D01*
X37141Y97894D01*
X37349Y97685D01*
X37641Y97602D01*
X37932Y97727D01*
X38141Y98019D01*
X38224Y98352D01*
X38141Y98685D01*
X37932Y98977D01*
X37641Y99102D01*
X37349Y99019D01*
X37141Y98810D01*
X37057Y98560D01*
Y98144D01*
X36932Y97769D01*
X36682Y97519D01*
X36391Y97435D01*
X36099Y97519D01*
X35891Y97727D01*
X35766Y98060D01*
X35724Y98352D01*
G01X40100Y96400D02*
X44100D01*
Y89000D01*
G01X37600Y78700D02*
Y82700D01*
X45000D01*
G01X79600Y66217D02*
X82100D01*
Y67217D01*
X81975Y67550D01*
X81683Y67800D01*
X81350Y67883D01*
X81017Y67800D01*
X80767Y67592D01*
X80642Y67217D01*
Y66217D01*
G01X81892Y71067D02*
X82017Y70817D01*
X82100Y70525D01*
Y70192D01*
X81975Y69817D01*
X81767Y69525D01*
X81517Y69317D01*
X81100Y69150D01*
X80725Y69108D01*
X80350Y69192D01*
X80100Y69317D01*
X79850Y69567D01*
X79683Y69858D01*
X79600Y70150D01*
Y70442D01*
X79683Y70733D01*
X79808Y70983D01*
X79975Y71192D01*
G01X79600Y73250D02*
X82100D01*
X81600Y72750D01*
G01X79600D02*
Y73750D01*
G01X81683Y75558D02*
X81933Y75808D01*
X82058Y76100D01*
X82100Y76433D01*
X82017Y76850D01*
X81808Y77142D01*
X81558Y77225D01*
X81308Y77183D01*
X81100Y77017D01*
X80683Y76183D01*
X80392Y75808D01*
X79975Y75558D01*
X79600Y75475D01*
Y77225D01*
G01X71200Y70417D02*
X73700D01*
Y71417D01*
X73575Y71750D01*
X73283Y72000D01*
X72950Y72083D01*
X72617Y72000D01*
X72367Y71792D01*
X72242Y71417D01*
Y70417D01*
G01X73700Y73433D02*
X71908D01*
X71533Y73600D01*
X71283Y73933D01*
X71200Y74350D01*
X71283Y74767D01*
X71533Y75100D01*
X71908Y75267D01*
X73700D01*
G01X71200Y77450D02*
X73700D01*
X73200Y76950D01*
G01X71200D02*
Y77950D01*
G01X61900Y57900D02*
X66900D01*
Y62900D01*
G01X61900Y81700D02*
X66900D01*
Y76700D01*
G01X47100D02*
Y81700D01*
X52100D01*
G01X58181Y58917D02*
Y55917D01*
G01X55819Y83683D02*
Y80683D01*
G01X67937Y69800D02*
X65937D01*
G01X46063D02*
X48063D01*
G01X39300Y20567D02*
X41800D01*
Y21567D01*
X41675Y21900D01*
X41383Y22150D01*
X41050Y22233D01*
X40717Y22150D01*
X40467Y21942D01*
X40342Y21567D01*
Y20567D01*
G01X41800Y23667D02*
X39300D01*
Y25333D01*
G01X41383Y26808D02*
X41633Y27058D01*
X41758Y27350D01*
X41800Y27683D01*
X41717Y28100D01*
X41508Y28392D01*
X41258Y28475D01*
X41008Y28433D01*
X40800Y28267D01*
X40383Y27433D01*
X40092Y27058D01*
X39675Y26808D01*
X39300Y26725D01*
Y28475D01*
G01X96300Y23667D02*
X98800D01*
Y24667D01*
X98675Y25000D01*
X98383Y25250D01*
X98050Y25333D01*
X97717Y25250D01*
X97467Y25042D01*
X97342Y24667D01*
Y23667D01*
G01X98592Y28517D02*
X98717Y28267D01*
X98800Y27975D01*
Y27642D01*
X98675Y27267D01*
X98467Y26975D01*
X98217Y26767D01*
X97800Y26600D01*
X97425Y26558D01*
X97050Y26642D01*
X96800Y26767D01*
X96550Y27017D01*
X96383Y27308D01*
X96300Y27600D01*
Y27892D01*
X96383Y28183D01*
X96508Y28433D01*
X96675Y28642D01*
G01X96592Y29992D02*
X96383Y30283D01*
X96300Y30617D01*
X96383Y30950D01*
X96633Y31242D01*
X97008Y31450D01*
X97383Y31533D01*
X97842D01*
X98217Y31450D01*
X98550Y31242D01*
X98717Y30992D01*
X98800Y30700D01*
X98717Y30367D01*
X98550Y30117D01*
X98300Y29950D01*
X97967Y29867D01*
X97675Y29950D01*
X97383Y30158D01*
X97217Y30408D01*
X97175Y30700D01*
X97258Y31033D01*
X97467Y31283D01*
X97842Y31533D01*
G01X96000Y41367D02*
X98500D01*
Y42367D01*
X98375Y42700D01*
X98083Y42950D01*
X97750Y43033D01*
X97417Y42950D01*
X97167Y42742D01*
X97042Y42367D01*
Y41367D01*
G01X98292Y46217D02*
X98417Y45967D01*
X98500Y45675D01*
Y45342D01*
X98375Y44967D01*
X98167Y44675D01*
X97917Y44467D01*
X97500Y44300D01*
X97125Y44258D01*
X96750Y44342D01*
X96500Y44467D01*
X96250Y44717D01*
X96083Y45008D01*
X96000Y45300D01*
Y45592D01*
X96083Y45883D01*
X96208Y46133D01*
X96375Y46342D01*
G01X96000Y48400D02*
X96042Y48692D01*
X96167Y49025D01*
X96375Y49233D01*
X96667Y49317D01*
X96958Y49233D01*
X97208Y48983D01*
X97333Y48608D01*
Y48192D01*
X97417Y47942D01*
X97625Y47733D01*
X97917Y47650D01*
X98208Y47775D01*
X98417Y48067D01*
X98500Y48400D01*
X98417Y48733D01*
X98208Y49025D01*
X97917Y49150D01*
X97625Y49067D01*
X97417Y48858D01*
X97333Y48608D01*
Y48192D01*
X97208Y47817D01*
X96958Y47567D01*
X96667Y47483D01*
X96375Y47567D01*
X96167Y47775D01*
X96042Y48108D01*
X96000Y48400D01*
G01X90500Y40667D02*
X93000D01*
Y41667D01*
X92875Y42000D01*
X92583Y42250D01*
X92250Y42333D01*
X91917Y42250D01*
X91667Y42042D01*
X91542Y41667D01*
Y40667D01*
G01X92792Y45517D02*
X92917Y45267D01*
X93000Y44975D01*
Y44642D01*
X92875Y44267D01*
X92667Y43975D01*
X92417Y43767D01*
X92000Y43600D01*
X91625Y43558D01*
X91250Y43642D01*
X91000Y43767D01*
X90750Y44017D01*
X90583Y44308D01*
X90500Y44600D01*
Y44892D01*
X90583Y45183D01*
X90708Y45433D01*
X90875Y45642D01*
G01X90500Y47617D02*
X91042Y47700D01*
X91500Y47825D01*
X91917Y47992D01*
X92375Y48200D01*
X93000Y48533D01*
Y46867D01*
G01X90600Y23867D02*
X93100D01*
Y24867D01*
X92975Y25200D01*
X92683Y25450D01*
X92350Y25533D01*
X92017Y25450D01*
X91767Y25242D01*
X91642Y24867D01*
Y23867D01*
G01X92892Y28717D02*
X93017Y28467D01*
X93100Y28175D01*
Y27842D01*
X92975Y27467D01*
X92767Y27175D01*
X92517Y26967D01*
X92100Y26800D01*
X91725Y26758D01*
X91350Y26842D01*
X91100Y26967D01*
X90850Y27217D01*
X90683Y27508D01*
X90600Y27800D01*
Y28092D01*
X90683Y28383D01*
X90808Y28633D01*
X90975Y28842D01*
G01X91642Y30108D02*
X91933Y30400D01*
X92100Y30650D01*
X92183Y30983D01*
X92100Y31275D01*
X91933Y31483D01*
X91683Y31650D01*
X91392Y31692D01*
X91142Y31650D01*
X90892Y31483D01*
X90683Y31233D01*
X90600Y30942D01*
X90683Y30608D01*
X90933Y30317D01*
X91308Y30150D01*
X91725Y30108D01*
X92267Y30192D01*
X92558Y30317D01*
X92850Y30525D01*
X93058Y30817D01*
X93100Y31108D01*
X93017Y31400D01*
X92808Y31608D01*
G01X206439Y17541D02*
X332910D01*
Y44082D01*
X206205D01*
Y17541D01*
X206439D01*
G01X206591Y-14772D02*
X333062D01*
Y11769D01*
X206357D01*
Y-14772D01*
X206591D01*
G01X206403Y51727D02*
X305213D01*
Y78138D01*
X206117D01*
Y51727D01*
X206403D01*
G54D14*
G01X25200Y62600D02*
X26300D01*
G01X22500D02*
X23600D01*
G01X38900Y52300D02*
X42900D01*
G01X42000Y83200D02*
Y87200D01*
G01X72800Y62900D02*
X68800D01*
M02*
